(kicad_pcb
	(version 20260206)
	(generator "pcbnew")
	(generator_version "10.0")
	(general
		(thickness 1.6)
		(legacy_teardrops no)
	)
	(paper "A4")
	(title_block
		(title "Bryce Canyon_SCC_16316-1_OCP.brd")
		(comment 1 "Bryce Canyon / footprints 199-206 of 1561")
	)
	(layers
		(0 "F.Cu" signal "TOP")
		(4 "In1.Cu" signal "L2GND")
		(6 "In2.Cu" signal "L3")
		(8 "In3.Cu" signal "L4VCC")
		(10 "In4.Cu" signal "L5VCC")
		(12 "In5.Cu" signal "L6")
		(14 "In6.Cu" signal "L7GND")
		(2 "B.Cu" signal "BOTTOM")
		(9 "F.Adhes" user "F.Adhesive")
		(11 "B.Adhes" user "B.Adhesive")
		(13 "F.Paste" user "Package Geometry/Pastemask Top")
		(15 "B.Paste" user "Package Geometry/Pastemask Bottom")
		(5 "F.SilkS" user "Ref Des/Silkscreen Top")
		(7 "B.SilkS" user "Ref Des/Silkscreen Bottom")
		(1 "F.Mask" user "Board Geometry/Soldermask Top")
		(3 "B.Mask" user "Board Geometry/Soldermask Bottom")
		(17 "Dwgs.User" user "User.Drawings")
		(19 "Cmts.User" user "User.Comments")
		(21 "Eco1.User" user "User.Eco1")
		(23 "Eco2.User" user "User.Eco2")
		(25 "Edge.Cuts" user "Board Geometry/Outline")
		(27 "Margin" user)
		(31 "F.CrtYd" user "Package Geometry/Place Bound Top")
		(29 "B.CrtYd" user "Package Geometry/Place Bound Bottom")
		(35 "F.Fab" user "Ref Des/Assembly Top")
		(33 "B.Fab" user "Ref Des/Assembly Bottom")
	)
	(footprint ""
		(layer "F.Cu")
		(at 23.74773 -85.799422 -90)
		(property "Reference" "C571"
			(at 0 0 270)
			(layer "F.SilkS")
			(hide yes)
			(effects
				(font
					(size 1.27 1.27)
				)
			)
		)
		(property "Value" "SCD1U16V2KX-3GP"
			(at 1.1811 -2.7051 270)
			(unlocked yes)
			(layer "F.Fab")
			(hide yes)
			(effects
				(font
					(size 1.016 1.016)
					(thickness 0.1524)
				)
			)
		)
		(property "Device Type" "C402H22"
			(at 1.1811 -4.2291 270)
			(unlocked yes)
			(layer "F.Fab")
			(hide yes)
			(effects
				(font
					(size 1.016 1.016)
					(thickness 0.1524)
				)
			)
		)
		(duplicate_pad_numbers_are_jumpers no)
		(fp_rect
			(start -0.4318 0.9525)
			(end 0.4318 -0.9525)
			(stroke
				(width 0)
				(type default)
			)
			(fill no)
			(layer "F.CrtYd")
		)
		(fp_rect
			(start -0.4318 0.9525)
			(end 0.4318 -0.9525)
			(stroke
				(width 0)
				(type default)
			)
			(fill no)
			(layer "F.Fab")
		)
		(pad "1" smd custom
			(at 0 -0.4445 270)
			(size 0.1524 0.1524)
			(layers "F.Cu" "F.Mask" "F.Paste")
			(net "P1V8_E")
			(options
				(clearance outline)
				(anchor circle)
			)
			(primitives
				(gr_poly
					(pts
						(arc
							(start 0.3048 -0.2032)
							(mid 0.275042 -0.275042)
							(end 0.2032 -0.3048)
						)
						(arc
							(start -0.2032 -0.3048)
							(mid -0.275042 -0.275042)
							(end -0.3048 -0.2032)
						)
						(arc
							(start -0.3048 0.2032)
							(mid -0.275042 0.275042)
							(end -0.2032 0.3048)
						)
						(arc
							(start 0.2032 0.3048)
							(mid 0.275042 0.275042)
							(end 0.3048 0.2032)
						)
					)
					(width 0)
					(fill yes)
				)
			)
		)
		(pad "2" smd custom
			(at 0 0.4445 270)
			(size 0.1524 0.1524)
			(layers "F.Cu" "F.Mask" "F.Paste")
			(net "GND")
			(options
				(clearance outline)
				(anchor circle)
			)
			(primitives
				(gr_poly
					(pts
						(arc
							(start 0.3048 -0.2032)
							(mid 0.275042 -0.275042)
							(end 0.2032 -0.3048)
						)
						(arc
							(start -0.2032 -0.3048)
							(mid -0.275042 -0.275042)
							(end -0.3048 -0.2032)
						)
						(arc
							(start -0.3048 0.2032)
							(mid -0.275042 0.275042)
							(end -0.2032 0.3048)
						)
						(arc
							(start 0.2032 0.3048)
							(mid 0.275042 0.275042)
							(end 0.3048 0.2032)
						)
					)
					(width 0)
					(fill yes)
				)
			)
		)
	)
	(footprint ""
		(layer "F.Cu")
		(at 24.8031 -114.9731 90)
		(property "Reference" "C523"
			(at 0 0 90)
			(layer "F.SilkS")
			(hide yes)
			(effects
				(font
					(size 1.27 1.27)
				)
			)
		)
		(property "Value" "SCD1U16V2KX-3GP"
			(at 1.1811 -2.7051 90)
			(unlocked yes)
			(layer "F.Fab")
			(hide yes)
			(effects
				(font
					(size 1.016 1.016)
					(thickness 0.1524)
				)
			)
		)
		(property "Device Type" "C402H22"
			(at 1.1811 -4.2291 90)
			(unlocked yes)
			(layer "F.Fab")
			(hide yes)
			(effects
				(font
					(size 1.016 1.016)
					(thickness 0.1524)
				)
			)
		)
		(duplicate_pad_numbers_are_jumpers no)
		(fp_rect
			(start -0.4318 0.9525)
			(end 0.4318 -0.9525)
			(stroke
				(width 0)
				(type default)
			)
			(fill no)
			(layer "F.CrtYd")
		)
		(fp_rect
			(start -0.4318 0.9525)
			(end 0.4318 -0.9525)
			(stroke
				(width 0)
				(type default)
			)
			(fill no)
			(layer "F.Fab")
		)
		(pad "1" smd custom
			(at 0 -0.4445 90)
			(size 0.1524 0.1524)
			(layers "F.Cu" "F.Mask" "F.Paste")
			(net "P5V")
			(options
				(clearance outline)
				(anchor circle)
			)
			(primitives
				(gr_poly
					(pts
						(arc
							(start 0.3048 -0.2032)
							(mid 0.275042 -0.275042)
							(end 0.2032 -0.3048)
						)
						(arc
							(start -0.2032 -0.3048)
							(mid -0.275042 -0.275042)
							(end -0.3048 -0.2032)
						)
						(arc
							(start -0.3048 0.2032)
							(mid -0.275042 0.275042)
							(end -0.2032 0.3048)
						)
						(arc
							(start 0.2032 0.3048)
							(mid 0.275042 0.275042)
							(end 0.3048 0.2032)
						)
					)
					(width 0)
					(fill yes)
				)
			)
		)
		(pad "2" smd custom
			(at 0 0.4445 90)
			(size 0.1524 0.1524)
			(layers "F.Cu" "F.Mask" "F.Paste")
			(net "GND")
			(options
				(clearance outline)
				(anchor circle)
			)
			(primitives
				(gr_poly
					(pts
						(arc
							(start 0.3048 -0.2032)
							(mid 0.275042 -0.275042)
							(end 0.2032 -0.3048)
						)
						(arc
							(start -0.2032 -0.3048)
							(mid -0.275042 -0.275042)
							(end -0.3048 -0.2032)
						)
						(arc
							(start -0.3048 0.2032)
							(mid -0.275042 0.275042)
							(end -0.2032 0.3048)
						)
						(arc
							(start 0.2032 0.3048)
							(mid 0.275042 0.275042)
							(end 0.3048 0.2032)
						)
					)
					(width 0)
					(fill yes)
				)
			)
		)
	)
	(footprint ""
		(layer "F.Cu")
		(at 142.86484 -118.50878 180)
		(property "Reference" "D3"
			(at 0 0 180)
			(layer "F.SilkS")
			(hide yes)
			(effects
				(font
					(size 1.27 1.27)
				)
			)
		)
		(property "Value" "RB551V30-GP"
			(at 0 -6.7818 180)
			(unlocked yes)
			(layer "F.Fab")
			(hide yes)
			(effects
				(font
					(size 1.016 1.016)
					(thickness 0.1524)
				)
			)
		)
		(property "Device Type" "SOD323AKH38"
			(at 0 -8.6868 180)
			(unlocked yes)
			(layer "F.Fab")
			(hide yes)
			(effects
				(font
					(size 1.016 1.016)
					(thickness 0.1524)
				)
			)
		)
		(duplicate_pad_numbers_are_jumpers no)
		(fp_line
			(start 0.889 2.159)
			(end -0.889 2.159)
			(stroke
				(width 0.1524)
				(type default)
			)
			(layer "F.SilkS")
		)
		(fp_line
			(start 0.889 -1.9304)
			(end 0.889 2.159)
			(stroke
				(width 0.1524)
				(type default)
			)
			(layer "F.SilkS")
		)
		(fp_line
			(start 0.762 2.0574)
			(end -0.762 2.0574)
			(stroke
				(width 0.508)
				(type default)
			)
			(layer "F.SilkS")
		)
		(fp_line
			(start -0.889 2.159)
			(end -0.889 -1.9304)
			(stroke
				(width 0.1524)
				(type default)
			)
			(layer "F.SilkS")
		)
		(fp_line
			(start -0.889 -1.9304)
			(end 0.889 -1.9304)
			(stroke
				(width 0.1524)
				(type default)
			)
			(layer "F.SilkS")
		)
		(fp_rect
			(start -1.016 2.3114)
			(end 1.016 -2.0066)
			(stroke
				(width 0)
				(type default)
			)
			(fill no)
			(layer "F.CrtYd")
		)
		(fp_poly
			(pts
				(xy -1.016 -2.0066) (xy 1.016 -2.0066) (xy 1.016 2.3114) (xy -1.016 2.3114)
			)
			(stroke
				(width 0)
				(type default)
			)
			(fill no)
			(layer "F.Fab")
		)
		(pad "A" smd rect
			(at 0 -1.143 180)
			(size 0.5588 1.016)
			(layers "F.Cu" "F.Mask" "F.Paste")
			(net "P1V5_C_S")
		)
		(pad "K" smd rect
			(at 0 1.143 180)
			(size 0.5588 1.016)
			(layers "F.Cu" "F.Mask" "F.Paste")
			(net "P1V8_C_PG")
		)
	)
	(footprint ""
		(layer "F.Cu")
		(at 152.155398 -71.124318 90)
		(property "Reference" "R352"
			(at 0 0 90)
			(layer "F.SilkS")
			(hide yes)
			(effects
				(font
					(size 1.27 1.27)
				)
			)
		)
		(property "Value" "1KR2F-3-GP"
			(at 0.064008 -3.993896 90)
			(unlocked yes)
			(layer "F.Fab")
			(hide yes)
			(effects
				(font
					(size 1.016 1.016)
					(thickness 0.1524)
				)
			)
		)
		(property "Device Type" "R402H16"
			(at 0.064008 -5.517896 90)
			(unlocked yes)
			(layer "F.Fab")
			(hide yes)
			(effects
				(font
					(size 1.016 1.016)
					(thickness 0.1524)
				)
			)
		)
		(duplicate_pad_numbers_are_jumpers no)
		(fp_line
			(start 0.508 -0.9398)
			(end -0.508 -0.9398)
			(stroke
				(width 0.1524)
				(type default)
			)
			(layer "F.SilkS")
		)
		(fp_line
			(start -0.508 -0.9398)
			(end -0.508 0.9398)
			(stroke
				(width 0.1524)
				(type default)
			)
			(layer "F.SilkS")
		)
		(fp_rect
			(start -0.508 0.9398)
			(end 0.508 -0.9398)
			(stroke
				(width 0)
				(type default)
			)
			(fill no)
			(layer "F.CrtYd")
		)
		(fp_rect
			(start -0.508 0.9398)
			(end 0.508 -0.9398)
			(stroke
				(width 0)
				(type default)
			)
			(fill no)
			(layer "F.Fab")
		)
		(pad "1" smd custom
			(at 0 -0.4445 90)
			(size 0.1397 0.1397)
			(layers "F.Cu" "F.Mask" "F.Paste")
			(net "P1V8_C")
			(options
				(clearance outline)
				(anchor circle)
			)
			(primitives
				(gr_poly
					(pts
						(arc
							(start -0.1778 -0.2794)
							(mid -0.249642 -0.249642)
							(end -0.2794 -0.1778)
						)
						(arc
							(start -0.2794 0.1778)
							(mid -0.249642 0.249642)
							(end -0.1778 0.2794)
						)
						(arc
							(start 0.1778 0.2794)
							(mid 0.249642 0.249642)
							(end 0.2794 0.1778)
						)
						(arc
							(start 0.2794 -0.1778)
							(mid 0.249642 -0.249642)
							(end 0.1778 -0.2794)
						)
					)
					(width 0)
					(fill yes)
				)
			)
		)
		(pad "2" smd custom
			(at 0 0.4445 90)
			(size 0.1397 0.1397)
			(layers "F.Cu" "F.Mask" "F.Paste")
			(net "P1V8_C_SENSE")
			(options
				(clearance outline)
				(anchor circle)
			)
			(primitives
				(gr_poly
					(pts
						(arc
							(start -0.1778 -0.2794)
							(mid -0.249642 -0.249642)
							(end -0.2794 -0.1778)
						)
						(arc
							(start -0.2794 0.1778)
							(mid -0.249642 0.249642)
							(end -0.1778 0.2794)
						)
						(arc
							(start 0.1778 0.2794)
							(mid 0.249642 0.249642)
							(end 0.2794 0.1778)
						)
						(arc
							(start 0.2794 -0.1778)
							(mid 0.249642 -0.249642)
							(end 0.1778 -0.2794)
						)
					)
					(width 0)
					(fill yes)
				)
			)
		)
	)
	(footprint ""
		(layer "F.Cu")
		(at 70.485 -58.674 90)
		(property "Reference" "L15"
			(at 0 0 90)
			(layer "F.SilkS")
			(hide yes)
			(effects
				(font
					(size 1.27 1.27)
				)
			)
		)
		(property "Value" "MPZ2012S300AT-GP"
			(at 0 -4.2418 90)
			(unlocked yes)
			(layer "F.Fab")
			(hide yes)
			(effects
				(font
					(size 1.016 1.016)
					(thickness 0.1524)
				)
			)
		)
		(property "Device Type" "L805H42"
			(at 0 -5.7912 90)
			(unlocked yes)
			(layer "F.Fab")
			(hide yes)
			(effects
				(font
					(size 1.016 1.016)
					(thickness 0.1524)
				)
			)
		)
		(duplicate_pad_numbers_are_jumpers no)
		(fp_line
			(start 0.889 -1.7018)
			(end 0.889 1.7018)
			(stroke
				(width 0.1524)
				(type default)
			)
			(layer "F.SilkS")
		)
		(fp_line
			(start -0.889 -1.7018)
			(end 0.889 -1.7018)
			(stroke
				(width 0.1524)
				(type default)
			)
			(layer "F.SilkS")
		)
		(fp_line
			(start 0.889 1.7018)
			(end -0.889 1.7018)
			(stroke
				(width 0.1524)
				(type default)
			)
			(layer "F.SilkS")
		)
		(fp_line
			(start -0.889 1.7018)
			(end -0.889 -1.7018)
			(stroke
				(width 0.1524)
				(type default)
			)
			(layer "F.SilkS")
		)
		(fp_rect
			(start -0.9652 1.778)
			(end 0.9652 -1.778)
			(stroke
				(width 0)
				(type default)
			)
			(fill no)
			(layer "F.CrtYd")
		)
		(fp_rect
			(start -0.9652 1.778)
			(end 0.9652 -1.778)
			(stroke
				(width 0)
				(type default)
			)
			(fill no)
			(layer "F.Fab")
		)
		(pad "1" smd rect
			(at 0 -0.9652 90)
			(size 1.397 1.143)
			(layers "F.Cu" "F.Mask" "F.Paste")
			(net "P0V9")
		)
		(pad "2" smd rect
			(at 0 0.9652 90)
			(size 1.397 1.143)
			(layers "F.Cu" "F.Mask" "F.Paste")
			(net "GB_VDDA")
		)
	)
	(footprint ""
		(layer "F.Cu")
		(at 38.3286 -34.671 -90)
		(property "Reference" "C712"
			(at 0 0 270)
			(layer "F.SilkS")
			(hide yes)
			(effects
				(font
					(size 1.27 1.27)
				)
			)
		)
		(property "Value" "SC1U16V2KX-7-GP"
			(at 1.7526 -1.6002 270)
			(unlocked yes)
			(layer "F.Fab")
			(hide yes)
			(effects
				(font
					(size 1.016 1.016)
					(thickness 0.1524)
				)
			)
		)
		(property "Device Type" "C402-TO0D2H24"
			(at 1.7526 -3.1242 270)
			(unlocked yes)
			(layer "F.Fab")
			(hide yes)
			(effects
				(font
					(size 1.016 1.016)
					(thickness 0.1524)
				)
			)
		)
		(duplicate_pad_numbers_are_jumpers no)
		(fp_rect
			(start -0.4826 0.889)
			(end 0.4826 -0.889)
			(stroke
				(width 0)
				(type default)
			)
			(fill no)
			(layer "F.CrtYd")
		)
		(fp_rect
			(start -0.4826 0.889)
			(end 0.4826 -0.889)
			(stroke
				(width 0)
				(type default)
			)
			(fill no)
			(layer "F.Fab")
		)
		(pad "1" smd custom
			(at 0 -0.4572 270)
			(size 0.1524 0.1524)
			(layers "F.Cu" "F.Mask" "F.Paste")
			(net "P0V9_EN")
			(options
				(clearance outline)
				(anchor circle)
			)
			(primitives
				(gr_poly
					(pts
						(arc
							(start -0.254 0.3048)
							(mid -0.325842 0.275042)
							(end -0.3556 0.2032)
						)
						(arc
							(start -0.3556 -0.2032)
							(mid -0.325842 -0.275042)
							(end -0.254 -0.3048)
						)
						(arc
							(start 0.254 -0.3048)
							(mid 0.325842 -0.275042)
							(end 0.3556 -0.2032)
						)
						(arc
							(start 0.3556 0.2032)
							(mid 0.325842 0.275042)
							(end 0.254 0.3048)
						)
					)
					(width 0)
					(fill yes)
				)
			)
		)
		(pad "2" smd custom
			(at 0 0.4572 270)
			(size 0.1524 0.1524)
			(layers "F.Cu" "F.Mask" "F.Paste")
			(net "GND")
			(options
				(clearance outline)
				(anchor circle)
			)
			(primitives
				(gr_poly
					(pts
						(arc
							(start -0.254 0.3048)
							(mid -0.325842 0.275042)
							(end -0.3556 0.2032)
						)
						(arc
							(start -0.3556 -0.2032)
							(mid -0.325842 -0.275042)
							(end -0.254 -0.3048)
						)
						(arc
							(start 0.254 -0.3048)
							(mid 0.325842 -0.275042)
							(end 0.3556 -0.2032)
						)
						(arc
							(start 0.3556 0.2032)
							(mid 0.325842 0.275042)
							(end 0.254 0.3048)
						)
					)
					(width 0)
					(fill yes)
				)
			)
		)
	)
	(footprint ""
		(layer "F.Cu")
		(at 176.5554 -96.52 180)
		(property "Reference" "R490"
			(at 0 0 180)
			(layer "F.SilkS")
			(hide yes)
			(effects
				(font
					(size 1.27 1.27)
				)
			)
		)
		(property "Value" "1K21R2F-2-GP"
			(at 0.064008 -3.993896 180)
			(unlocked yes)
			(layer "F.Fab")
			(hide yes)
			(effects
				(font
					(size 1.016 1.016)
					(thickness 0.1524)
				)
			)
		)
		(property "Device Type" "R402H16"
			(at 0.064008 -5.517896 180)
			(unlocked yes)
			(layer "F.Fab")
			(hide yes)
			(effects
				(font
					(size 1.016 1.016)
					(thickness 0.1524)
				)
			)
		)
		(duplicate_pad_numbers_are_jumpers no)
		(fp_line
			(start 0.508 -0.9398)
			(end -0.508 -0.9398)
			(stroke
				(width 0.1524)
				(type default)
			)
			(layer "F.SilkS")
		)
		(fp_line
			(start -0.508 -0.9398)
			(end -0.508 0.9398)
			(stroke
				(width 0.1524)
				(type default)
			)
			(layer "F.SilkS")
		)
		(fp_rect
			(start -0.508 0.9398)
			(end 0.508 -0.9398)
			(stroke
				(width 0)
				(type default)
			)
			(fill no)
			(layer "F.CrtYd")
		)
		(fp_rect
			(start -0.508 0.9398)
			(end 0.508 -0.9398)
			(stroke
				(width 0)
				(type default)
			)
			(fill no)
			(layer "F.Fab")
		)
		(pad "1" smd custom
			(at 0 -0.4445 180)
			(size 0.1397 0.1397)
			(layers "F.Cu" "F.Mask" "F.Paste")
			(net "VT235_VFB")
			(options
				(clearance outline)
				(anchor circle)
			)
			(primitives
				(gr_poly
					(pts
						(arc
							(start -0.1778 -0.2794)
							(mid -0.249642 -0.249642)
							(end -0.2794 -0.1778)
						)
						(arc
							(start -0.2794 0.1778)
							(mid -0.249642 0.249642)
							(end -0.1778 0.2794)
						)
						(arc
							(start 0.1778 0.2794)
							(mid 0.249642 0.249642)
							(end 0.2794 0.1778)
						)
						(arc
							(start 0.2794 -0.1778)
							(mid 0.249642 -0.249642)
							(end 0.1778 -0.2794)
						)
					)
					(width 0)
					(fill yes)
				)
			)
		)
		(pad "2" smd custom
			(at 0 0.4445 180)
			(size 0.1397 0.1397)
			(layers "F.Cu" "F.Mask" "F.Paste")
			(net "VT235_VDES_RC")
			(options
				(clearance outline)
				(anchor circle)
			)
			(primitives
				(gr_poly
					(pts
						(arc
							(start -0.1778 -0.2794)
							(mid -0.249642 -0.249642)
							(end -0.2794 -0.1778)
						)
						(arc
							(start -0.2794 0.1778)
							(mid -0.249642 0.249642)
							(end -0.1778 0.2794)
						)
						(arc
							(start 0.1778 0.2794)
							(mid 0.249642 0.249642)
							(end 0.2794 0.1778)
						)
						(arc
							(start 0.2794 -0.1778)
							(mid 0.249642 -0.249642)
							(end 0.1778 -0.2794)
						)
					)
					(width 0)
					(fill yes)
				)
			)
		)
	)
	(footprint ""
		(layer "F.Cu")
		(at 130.239516 -87.244936 180)
		(property "Reference" "R100"
			(at 0 0 180)
			(layer "F.SilkS")
			(hide yes)
			(effects
				(font
					(size 1.27 1.27)
				)
			)
		)
		(property "Value" "0R2J-2-GP"
			(at 0.064008 -3.993896 180)
			(unlocked yes)
			(layer "F.Fab")
			(hide yes)
			(effects
				(font
					(size 1.016 1.016)
					(thickness 0.1524)
				)
			)
		)
		(property "Device Type" "R402H16"
			(at 0.064008 -5.517896 180)
			(unlocked yes)
			(layer "F.Fab")
			(hide yes)
			(effects
				(font
					(size 1.016 1.016)
					(thickness 0.1524)
				)
			)
		)
		(duplicate_pad_numbers_are_jumpers no)
		(fp_line
			(start 0.508 -0.9398)
			(end -0.508 -0.9398)
			(stroke
				(width 0.1524)
				(type default)
			)
			(layer "F.SilkS")
		)
		(fp_line
			(start -0.508 -0.9398)
			(end -0.508 0.9398)
			(stroke
				(width 0.1524)
				(type default)
			)
			(layer "F.SilkS")
		)
		(fp_rect
			(start -0.508 0.9398)
			(end 0.508 -0.9398)
			(stroke
				(width 0)
				(type default)
			)
			(fill no)
			(layer "F.CrtYd")
		)
		(fp_rect
			(start -0.508 0.9398)
			(end 0.508 -0.9398)
			(stroke
				(width 0)
				(type default)
			)
			(fill no)
			(layer "F.Fab")
		)
		(pad "1" smd custom
			(at 0 -0.4445 180)
			(size 0.1397 0.1397)
			(layers "F.Cu" "F.Mask" "F.Paste")
			(net "SMART_RX")
			(options
				(clearance outline)
				(anchor circle)
			)
			(primitives
				(gr_poly
					(pts
						(arc
							(start -0.1778 -0.2794)
							(mid -0.249642 -0.249642)
							(end -0.2794 -0.1778)
						)
						(arc
							(start -0.2794 0.1778)
							(mid -0.249642 0.249642)
							(end -0.1778 0.2794)
						)
						(arc
							(start 0.1778 0.2794)
							(mid 0.249642 0.249642)
							(end 0.2794 0.1778)
						)
						(arc
							(start 0.2794 -0.1778)
							(mid 0.249642 -0.249642)
							(end 0.1778 -0.2794)
						)
					)
					(width 0)
					(fill yes)
				)
			)
		)
		(pad "2" smd custom
			(at 0 0.4445 180)
			(size 0.1397 0.1397)
			(layers "F.Cu" "F.Mask" "F.Paste")
			(net "SAS_SMART_RX")
			(options
				(clearance outline)
				(anchor circle)
			)
			(primitives
				(gr_poly
					(pts
						(arc
							(start -0.1778 -0.2794)
							(mid -0.249642 -0.249642)
							(end -0.2794 -0.1778)
						)
						(arc
							(start -0.2794 0.1778)
							(mid -0.249642 0.249642)
							(end -0.1778 0.2794)
						)
						(arc
							(start 0.1778 0.2794)
							(mid 0.249642 0.249642)
							(end 0.2794 0.1778)
						)
						(arc
							(start 0.2794 -0.1778)
							(mid 0.249642 -0.249642)
							(end 0.1778 -0.2794)
						)
					)
					(width 0)
					(fill yes)
				)
			)
		)
	)
)
